# S9S_MB_2U (Grand Teton) — schematic netlist excerpt (pin names and nets, part order shuffled) for the footprints in the layout excerpt that follows; sources: Cadence DE-HDL packaged netlist, KiCad conversion of 03242023_DA0F0TMBIJ0_F0T_Motherboard_J_brd_V01_OCP.brd

PC1372  Q_CAP  1UF 16V 10% X6S  pkg C0402  page 274 : A = PVCCINFAON_CPU0_VREF ; B = GND
R913  Q_RES  10K 1% CHIP  pkg 0402LF  page 183 : A = PU_OC6_USB_N ; B = P3V3_AUX

(kicad_pcb
	(version 20260206)
	(generator "pcbnew")
	(generator_version "10.0")
	(general
		(thickness 1.6)
		(legacy_teardrops no)
	)
	(paper "A4")
	(title_block
		(title "03242023_DA0F0TMBIJ0_F0T_Motherboard_J_brd_V01_OCP.brd")
		(comment 1 "Grand Teton / footprints 965-966 of 6105")
	)
	(layers
		(0 "F.Cu" signal "TOP")
		(4 "In1.Cu" signal "GND")
		(6 "In2.Cu" signal "IN1")
		(8 "In3.Cu" signal "GND1")
		(10 "In4.Cu" signal "IN2")
		(12 "In5.Cu" signal "GND2")
		(14 "In6.Cu" signal "IN3")
		(16 "In7.Cu" signal "GND3")
		(18 "In8.Cu" signal "VCC")
		(20 "In9.Cu" signal "VCC1")
		(22 "In10.Cu" signal "GND4")
		(24 "In11.Cu" signal "IN4")
		(26 "In12.Cu" signal "GND5")
		(28 "In13.Cu" signal "IN5")
		(30 "In14.Cu" signal "GND6")
		(32 "In15.Cu" signal "IN6")
		(34 "In16.Cu" signal "GND7")
		(2 "B.Cu" signal "BOTTOM")
		(9 "F.Adhes" user "F.Adhesive")
		(11 "B.Adhes" user "B.Adhesive")
		(13 "F.Paste" user "Package Geometry/Pastemask Top")
		(15 "B.Paste" user "Package Geometry/Pastemask Bottom")
		(5 "F.SilkS" user "Ref Des/Silkscreen Top")
		(7 "B.SilkS" user "Ref Des/Silkscreen Bottom")
		(1 "F.Mask" user "Board Geometry/Soldermask Top")
		(3 "B.Mask" user "Board Geometry/Soldermask Bottom")
		(17 "Dwgs.User" user "User.Drawings")
		(19 "Cmts.User" user "User.Comments")
		(21 "Eco1.User" user "User.Eco1")
		(23 "Eco2.User" user "User.Eco2")
		(25 "Edge.Cuts" user "Board Geometry/Outline")
		(27 "Margin" user)
		(31 "F.CrtYd" user "Package Geometry/Place Bound Top")
		(29 "B.CrtYd" user "Package Geometry/Place Bound Bottom")
		(35 "F.Fab" user "Ref Des/Assembly Top")
		(33 "B.Fab" user "Ref Des/Assembly Bottom")
	)
	(footprint ""
		(layer "F.Cu")
		(at 422.497504 -131.975352 -90)
		(property "Reference" "PC1372"
			(at 0 0 270)
			(layer "F.SilkS")
			(hide yes)
			(effects
				(font
					(size 1.27 1.27)
				)
			)
		)
		(property "Value" ""
			(at 0 0 270)
			(layer "F.Fab")
			(effects
				(font
					(size 1.27 1.27)
				)
			)
		)
		(duplicate_pad_numbers_are_jumpers no)
		(fp_line
			(start -0.7874 0.4064)
			(end -0.7874 -0.4064)
			(stroke
				(width 0.1524)
				(type default)
			)
			(layer "F.SilkS")
		)
		(fp_line
			(start 0.7874 0.4064)
			(end -0.7874 0.4064)
			(stroke
				(width 0.1524)
				(type default)
			)
			(layer "F.SilkS")
		)
		(fp_line
			(start -0.7874 -0.4064)
			(end 0.7874 -0.4064)
			(stroke
				(width 0.1524)
				(type default)
			)
			(layer "F.SilkS")
		)
		(fp_line
			(start 0.7874 -0.4064)
			(end 0.7874 0.4064)
			(stroke
				(width 0.1524)
				(type default)
			)
			(layer "F.SilkS")
		)
		(fp_line
			(start -0.67945 0.3048)
			(end -0.67945 -0.305054)
			(stroke
				(width 0.1)
				(type default)
			)
			(layer "F.Fab")
		)
		(fp_line
			(start -0.12065 0.3048)
			(end -0.67945 0.3048)
			(stroke
				(width 0.1)
				(type default)
			)
			(layer "F.Fab")
		)
		(fp_line
			(start 0.120396 0.3048)
			(end 0.120396 0.2794)
			(stroke
				(width 0.1)
				(type default)
			)
			(layer "F.Fab")
		)
		(fp_line
			(start 0.67945 0.3048)
			(end 0.120396 0.3048)
			(stroke
				(width 0.1)
				(type default)
			)
			(layer "F.Fab")
		)
		(fp_line
			(start -0.12065 0.2794)
			(end -0.12065 0.3048)
			(stroke
				(width 0.1)
				(type default)
			)
			(layer "F.Fab")
		)
		(fp_line
			(start 0.120396 0.2794)
			(end -0.12065 0.2794)
			(stroke
				(width 0.1)
				(type default)
			)
			(layer "F.Fab")
		)
		(fp_line
			(start -0.12065 -0.2794)
			(end 0.12065 -0.2794)
			(stroke
				(width 0.1)
				(type default)
			)
			(layer "F.Fab")
		)
		(fp_line
			(start 0.12065 -0.2794)
			(end 0.12065 -0.3048)
			(stroke
				(width 0.1)
				(type default)
			)
			(layer "F.Fab")
		)
		(fp_line
			(start 0.12065 -0.3048)
			(end 0.67945 -0.3048)
			(stroke
				(width 0.1)
				(type default)
			)
			(layer "F.Fab")
		)
		(fp_line
			(start 0.67945 -0.3048)
			(end 0.67945 0.3048)
			(stroke
				(width 0.1)
				(type default)
			)
			(layer "F.Fab")
		)
		(fp_line
			(start -0.67945 -0.305054)
			(end -0.12065 -0.305054)
			(stroke
				(width 0.1)
				(type default)
			)
			(layer "F.Fab")
		)
		(fp_line
			(start -0.12065 -0.305054)
			(end -0.12065 -0.2794)
			(stroke
				(width 0.1)
				(type default)
			)
			(layer "F.Fab")
		)
		(pad "1" smd circle
			(at -0.40005 0 270)
			(size 0 0)
			(layers "F.Cu" "F.Mask" "F.Paste")
			(net "PVCCINFAON_CPU0_VREF")
		)
		(pad "2" smd circle
			(at 0.40005 0 270)
			(size 0 0)
			(layers "F.Cu" "F.Mask" "F.Paste")
			(net "GND")
		)
	)
	(footprint ""
		(layer "F.Cu")
		(at 337.730084 -27.678126 -90)
		(property "Reference" "R913"
			(at 0 0 270)
			(layer "F.SilkS")
			(hide yes)
			(effects
				(font
					(size 1.27 1.27)
				)
			)
		)
		(property "Value" ""
			(at 0 0 270)
			(layer "F.Fab")
			(effects
				(font
					(size 1.27 1.27)
				)
			)
		)
		(duplicate_pad_numbers_are_jumpers no)
		(fp_line
			(start -0.7874 0.4064)
			(end -0.7874 -0.4064)
			(stroke
				(width 0.1524)
				(type default)
			)
			(layer "F.SilkS")
		)
		(fp_line
			(start 0.7874 0.4064)
			(end -0.7874 0.4064)
			(stroke
				(width 0.1524)
				(type default)
			)
			(layer "F.SilkS")
		)
		(fp_line
			(start -0.7874 -0.4064)
			(end 0.7874 -0.4064)
			(stroke
				(width 0.1524)
				(type default)
			)
			(layer "F.SilkS")
		)
		(fp_line
			(start 0.7874 -0.4064)
			(end 0.7874 0.4064)
			(stroke
				(width 0.1524)
				(type default)
			)
			(layer "F.SilkS")
		)
		(fp_line
			(start -0.67945 0.3048)
			(end -0.67945 -0.305054)
			(stroke
				(width 0.1)
				(type default)
			)
			(layer "F.Fab")
		)
		(fp_line
			(start -0.12065 0.3048)
			(end -0.67945 0.3048)
			(stroke
				(width 0.1)
				(type default)
			)
			(layer "F.Fab")
		)
		(fp_line
			(start 0.120396 0.3048)
			(end 0.120396 0.2794)
			(stroke
				(width 0.1)
				(type default)
			)
			(layer "F.Fab")
		)
		(fp_line
			(start 0.67945 0.3048)
			(end 0.120396 0.3048)
			(stroke
				(width 0.1)
				(type default)
			)
			(layer "F.Fab")
		)
		(fp_line
			(start -0.12065 0.2794)
			(end -0.12065 0.3048)
			(stroke
				(width 0.1)
				(type default)
			)
			(layer "F.Fab")
		)
		(fp_line
			(start 0.120396 0.2794)
			(end -0.12065 0.2794)
			(stroke
				(width 0.1)
				(type default)
			)
			(layer "F.Fab")
		)
		(fp_line
			(start -0.12065 -0.2794)
			(end 0.12065 -0.2794)
			(stroke
				(width 0.1)
				(type default)
			)
			(layer "F.Fab")
		)
		(fp_line
			(start 0.12065 -0.2794)
			(end 0.12065 -0.3048)
			(stroke
				(width 0.1)
				(type default)
			)
			(layer "F.Fab")
		)
		(fp_line
			(start 0.12065 -0.3048)
			(end 0.67945 -0.3048)
			(stroke
				(width 0.1)
				(type default)
			)
			(layer "F.Fab")
		)
		(fp_line
			(start 0.67945 -0.3048)
			(end 0.67945 0.3048)
			(stroke
				(width 0.1)
				(type default)
			)
			(layer "F.Fab")
		)
		(fp_line
			(start -0.67945 -0.305054)
			(end -0.12065 -0.305054)
			(stroke
				(width 0.1)
				(type default)
			)
			(layer "F.Fab")
		)
		(fp_line
			(start -0.12065 -0.305054)
			(end -0.12065 -0.2794)
			(stroke
				(width 0.1)
				(type default)
			)
			(layer "F.Fab")
		)
		(pad "1" smd circle
			(at -0.40005 0 270)
			(size 0 0)
			(layers "F.Cu" "F.Mask" "F.Paste")
			(net "PU_OC6_USB_N")
		)
		(pad "2" smd circle
			(at 0.40005 0 270)
			(size 0 0)
			(layers "F.Cu" "F.Mask" "F.Paste")
			(net "P3V3_AUX")
		)
	)
)
